# T6G (Grand Teton) — schematic netlist excerpt (pin names and nets, part order shuffled) for the footprints in the layout excerpt that follows; sources: Cadence DE-HDL packaged netlist, KiCad conversion of 04192023_DAF0TMB3IC0_F0TG_MB_C_brd_V02_OCP.brd

J17  SCONN288_DDR506112002KQ  IO  pkg DDR288S_1-1VXC  page 88
  VIN_BULK0  = P12V_MEM_CPU0
  RFU0  = NC
  VIN_MGMT  = P3V3_AUX
  HSCL  = I3C_SPD_DDRC_CPU0_SCL
  HSDA  = I3C_SPD_DDRC_CPU0_SDA
  VSS0  = GND
  DQ0_A  = M_C_CPU0_SA_DQ<0>
  VSS1  = GND
  DQ1_A  = M_C_CPU0_SA_DQ<1>
  VSS2  = GND
  DQS0_A_T  = M_C_CPU0_SA_DQS_DP<0>
  DQS0_A_C  = M_C_CPU0_SA_DQS_DN<0>
  VSS3  = GND
  DQ4_A  = M_C_CPU0_SA_DQ<4>
  VSS4  = GND
  DQ5_A  = M_C_CPU0_SA_DQ<5>
  VSS5  = GND
  DQ8_A  = M_C_CPU0_SA_DQ<8>
  VSS6  = GND
  DQ9_A  = M_C_CPU0_SA_DQ<9>
  VSS7  = GND
  DQS1_A_T  = M_C_CPU0_SA_DQS_DP<1>
  DQS1_A_C  = M_C_CPU0_SA_DQS_DN<1>
  VSS8  = GND
  DQ12_A  = M_C_CPU0_SA_DQ<12>
  VSS9  = GND
  DQ13_A  = M_C_CPU0_SA_DQ<13>
  VSS10  = GND
  DQ16_A  = M_C_CPU0_SA_DQ<16>
  VSS11  = GND
  DQ17_A  = M_C_CPU0_SA_DQ<17>
  VSS12  = GND
  DQS2_A_T  = M_C_CPU0_SA_DQS_DP<2>
  DQS2_A_C  = M_C_CPU0_SA_DQS_DN<2>
  VSS13  = GND
  DQ20_A  = M_C_CPU0_SA_DQ<20>
  VSS14  = GND
  DQ21_A  = M_C_CPU0_SA_DQ<21>
  VSS15  = GND
  DQ24_A  = M_C_CPU0_SA_DQ<24>
  VSS16  = GND
  DQ25_A  = M_C_CPU0_SA_DQ<25>
  VSS17  = GND
  DQS3_A_T  = M_C_CPU0_SA_DQS_DP<3>
  DQS3_A_C  = M_C_CPU0_SA_DQS_DN<3>
  VSS18  = GND
  DQ28_A  = M_C_CPU0_SA_DQ<28>
  VSS19  = GND
  DQ29_A  = M_C_CPU0_SA_DQ<29>
  VSS20  = GND
  CB0_A  = M_C_CPU0_SA_CB<0>
  VSS21  = GND
  CB1_A  = M_C_CPU0_SA_CB<1>
  VSS22  = GND
  DQS4_A_T  = M_C_CPU0_SA_DQS_DP<4>
  DQS4_A_C  = M_C_CPU0_SA_DQS_DN<4>
  VSS23  = GND
  CB4_A  = M_C_CPU0_SA_CB<4>
  VSS24  = GND
  CB5_A  = M_C_CPU0_SA_CB<5>
  VSS25  = GND
  ALERT_N  = M_C_CPU0_ALERT_N
  VSS26  = GND
  CS0_A_N  = M_C_CPU0_SA_CS_N<0>
  VSS27  = GND
  CA0_A  = M_C_CPU0_SA_CA<0>
  VSS28  = GND
  CA2_A  = M_C_CPU0_SA_CA<2>
  VSS29  = GND
  CA4_A  = M_C_CPU0_SA_CA<4>
  VSS30  = GND
  CA6_A  = M_C_CPU0_SA_CA<6>
  VSS31  = GND
  PAR_A  = M_C_CPU0_SA_PAR
  VSS32  = GND
  CA0_B  = M_C_CPU0_SB_CA<0>
  VSS33  = GND
  CA2_B  = M_C_CPU0_SB_CA<2>
  VSS34  = GND
  CA4_B  = M_C_CPU0_SB_CA<4>
  VSS35  = GND
  CA6_B  = M_C_CPU0_SB_CA<6>
  VSS36  = GND
  CS0_B_N  = M_C_CPU0_SB_CS_N<0>
  VSS37  = GND
  \lbd||rsp_a_n\  = M_C_CPU0_SA_RSP<0>
  \lbs||rsp_b_n\  = M_C_CPU0_SB_RSP<0>
  VSS38  = GND
  CB4_B  = M_C_CPU0_SB_CB<4>
  VSS39  = GND
  CB5_B  = M_C_CPU0_SB_CB<5>
  VSS40  = GND
  \dqs9_b_t||tdqs9_b_t||dbi4_b_n\  = M_C_CPU0_SB_DQS_DP<9>
  \dqs9_b_c||tdqs9_b_c\  = M_C_CPU0_SB_DQS_DN<9>
  VSS41  = GND
  CB0_B  = M_C_CPU0_SB_CB<0>
  VSS42  = GND
  CB1_B  = M_C_CPU0_SB_CB<1>
  VSS43  = GND
  DQ0_B  = M_C_CPU0_SB_DQ<0>
  VSS44  = GND
  DQ1_B  = M_C_CPU0_SB_DQ<1>
  VSS45  = GND
  DQS0_B_T  = M_C_CPU0_SB_DQS_DP<0>
  DQS0_B_C  = M_C_CPU0_SB_DQS_DN<0>
  VSS46  = GND
  DQ4_B  = M_C_CPU0_SB_DQ<4>
  VSS47  = GND
  DQ5_B  = M_C_CPU0_SB_DQ<5>
  VSS48  = GND
  DQ8_B  = M_C_CPU0_SB_DQ<8>
  VSS49  = GND
  DQ9_B  = M_C_CPU0_SB_DQ<9>
  VSS50  = GND
  DQS1_B_T  = M_C_CPU0_SB_DQS_DP<1>
  DQS1_B_C  = M_C_CPU0_SB_DQS_DN<1>
  VSS51  = GND
  DQ12_B  = M_C_CPU0_SB_DQ<12>
  VSS52  = GND
  DQ13_B  = M_C_CPU0_SB_DQ<13>
  VSS53  = GND
  DQ16_B  = M_C_CPU0_SB_DQ<16>
  VSS54  = GND
  DQ17_B  = M_C_CPU0_SB_DQ<17>
  VSS55  = GND
  DQS2_B_T  = M_C_CPU0_SB_DQS_DP<2>
  DQS2_B_C  = M_C_CPU0_SB_DQS_DN<2>
  VSS56  = GND
  DQ20_B  = M_C_CPU0_SB_DQ<20>
  VSS57  = GND
  DQ21_B  = M_C_CPU0_SB_DQ<21>
  VSS58  = GND
  DQ24_B  = M_C_CPU0_SB_DQ<24>
  VSS59  = GND
  DQ25_B  = M_C_CPU0_SB_DQ<25>
  VSS60  = GND
  DQS3_B_T  = M_C_CPU0_SB_DQS_DP<3>
  DQS3_B_C  = M_C_CPU0_SB_DQS_DN<3>
  VSS61  = GND
  DQ28_B  = M_C_CPU0_SB_DQ<28>
  VSS62  = GND
  DQ29_B  = M_C_CPU0_SB_DQ<29>
  VSS63  = GND
  RFU1  = NC
  VIN_BULK1  = P12V_MEM_CPU0
  VIN_BULK2  = P12V_MEM_CPU0
  \pwr_good||fail_n\  = PWRGD_CHC_CPU0_DIMM
  HAS  = PD_CHC_CPU0_DIMM_SAA
  RFU2  = NC
  RFU3  = NC
  VSS64  = GND
  DQ2_A  = M_C_CPU0_SA_DQ<2>
  VSS65  = GND
  DQ3_A  = M_C_CPU0_SA_DQ<3>
  VSS66  = GND
  \dqs5_a_c||tdqs5_a_c||dqs5_a_t||tdqs5_a_t\  = M_C_CPU0_SA_DQS_DN<5>
  \dqs5_a_t||tdqs5_a_t\  = M_C_CPU0_SA_DQS_DP<5>
  VSS67  = GND
  DQ6_A  = M_C_CPU0_SA_DQ<6>
  VSS68  = GND
  DQ7_A  = M_C_CPU0_SA_DQ<7>
  VSS69  = GND
  DQ10_A  = M_C_CPU0_SA_DQ<10>
  VSS70  = GND
  DQ11_A  = M_C_CPU0_SA_DQ<11>
  VSS71  = GND
  \dqs6_a_c||tdqs6_a_c||dqs6_a_t||tdqs6_a_t\  = M_C_CPU0_SA_DQS_DN<6>
  \dqs6_a_t||tdqs6_a_t\  = M_C_CPU0_SA_DQS_DP<6>
  VSS72  = GND
  DQ14_A  = M_C_CPU0_SA_DQ<14>
  VSS73  = GND
  DQ15_A  = M_C_CPU0_SA_DQ<15>
  VSS74  = GND
  DQ18_A  = M_C_CPU0_SA_DQ<18>
  VSS75  = GND
  DQ19_A  = M_C_CPU0_SA_DQ<19>
  VSS76  = GND
  \dqs7_a_c||tdqs7_a_c\  = M_C_CPU0_SA_DQS_DN<7>
  \dqs7_a_t||tdqs7_a_t\  = M_C_CPU0_SA_DQS_DP<7>
  VSS77  = GND
  DQ22_A  = M_C_CPU0_SA_DQ<22>
  VSS78  = GND
  DQ23_A  = M_C_CPU0_SA_DQ<23>
  VSS79  = GND
  DQ26_A  = M_C_CPU0_SA_DQ<26>
  VSS80  = GND
  DQ27_A  = M_C_CPU0_SA_DQ<27>
  VSS81  = GND
  \dqs8_a_c||tdqs8_a_c\  = M_C_CPU0_SA_DQS_DN<8>
  \dqs8_a_t||tdqs8_a_t\  = M_C_CPU0_SA_DQS_DP<8>
  VSS82  = GND
  DQ30_A  = M_C_CPU0_SA_DQ<30>
  VSS83  = GND
  DQ31_A  = M_C_CPU0_SA_DQ<31>
  VSS84  = GND
  CB2_A  = M_C_CPU0_SA_CB<2>
  VSS85  = GND
  CB3_A  = M_C_CPU0_SA_CB<3>
  VSS86  = GND
  \dqs9_a_c||tdqs9_a_c\  = M_C_CPU0_SA_DQS_DN<9>
  \dqs9_a_t||tdqs9_a_t\  = M_C_CPU0_SA_DQS_DP<9>
  VSS87  = GND
  CB6_A  = M_C_CPU0_SA_CB<6>
  VSS88  = GND
  CB7_A  = M_C_CPU0_SA_CB<7>
  VSS89  = GND
  RESET_N  = M_C_CPU0_RESET_N
  VSS90  = GND
  CS1_A_N  = M_C_CPU0_SA_CS_N<1>
  VSS91  = GND
  CA1_A  = M_C_CPU0_SA_CA<1>
  VSS92  = GND
  CA3_A  = M_C_CPU0_SA_CA<3>
  VSS93  = GND
  CA5_A  = M_C_CPU0_SA_CA<5>
  VSS94  = GND
  CK_T  = M_C_CPU0_CLK_DP<0>
  CK_C  = M_C_CPU0_CLK_DN<0>
  VSS95  = GND
  RFU4  = NC
  CA1_B  = M_C_CPU0_SB_CA<1>
  VSS96  = GND
  CA3_B  = M_C_CPU0_SB_CA<3>
  VSS97  = GND
  CA5_B  = M_C_CPU0_SB_CA<5>
  VSS98  = GND
  PAR_B  = M_C_CPU0_SB_PAR
  VSS99  = GND
  CS1_B_N  = M_C_CPU0_SB_CS_N<1>
  VSS100  = GND
  RFU5  = NC
  RFU6  = NC
  VSS101  = GND
  CB6_B  = M_C_CPU0_SB_CB<6>
  VSS102  = GND
  CB7_B  = M_C_CPU0_SB_CB<7>
  VSS103  = GND
  DQS4_B_C  = M_C_CPU0_SB_DQS_DN<4>
  DQS4_B_T  = M_C_CPU0_SB_DQS_DP<4>
  VSS104  = GND
  CB2_B  = M_C_CPU0_SB_CB<2>
  VSS105  = GND
  CB3_B  = M_C_CPU0_SB_CB<3>
  VSS106  = GND
  DQ2_B  = M_C_CPU0_SB_DQ<2>
  VSS107  = GND
  DQ3_B  = M_C_CPU0_SB_DQ<3>
  VSS108  = GND
  \dqs5_b_c||tdqs5_b_c\  = M_C_CPU0_SB_DQS_DN<5>
  \dqs5_b_t||tdqs5_b_t\  = M_C_CPU0_SB_DQS_DP<5>
  VSS109  = GND
  DQ6_B  = M_C_CPU0_SB_DQ<6>
  VSS110  = GND
  DQ7_B  = M_C_CPU0_SB_DQ<7>
  VSS111  = GND
  DQ10_B  = M_C_CPU0_SB_DQ<10>
  VSS112  = GND
  DQ11_B  = M_C_CPU0_SB_DQ<11>
  VSS113  = GND
  \dqs6_b_c||tdqs6_b_c\  = M_C_CPU0_SB_DQS_DN<6>
  \dqs6_b_t||tdqs6_b_t\  = M_C_CPU0_SB_DQS_DP<6>
  VSS114  = GND
  DQ14_B  = M_C_CPU0_SB_DQ<14>
  VSS115  = GND
  DQ15_B  = M_C_CPU0_SB_DQ<15>
  VSS116  = GND
  DQ18_B  = M_C_CPU0_SB_DQ<18>
  VSS117  = GND
  DQ19_B  = M_C_CPU0_SB_DQ<19>
  VSS118  = GND
  \dqs7_b_c||tdqs7_b_c\  = M_C_CPU0_SB_DQS_DN<7>
  \dqs7_b_t||tdqs7_b_t\  = M_C_CPU0_SB_DQS_DP<7>
  VSS119  = GND
  DQ22_B  = M_C_CPU0_SB_DQ<22>
  VSS120  = GND
  DQ23_B  = M_C_CPU0_SB_DQ<23>
  VSS121  = GND
  DQ26_B  = M_C_CPU0_SB_DQ<26>
  VSS122  = GND
  DQ27_B  = M_C_CPU0_SB_DQ<27>
  VSS123  = GND
  \dqs8_b_c||tdqs8_b_c\  = M_C_CPU0_SB_DQS_DN<8>
  \dqs8_b_t||tdqs8_b_t\  = M_C_CPU0_SB_DQS_DP<8>
  VSS124  = GND
  DQ30_B  = M_C_CPU0_SB_DQ<30>
  VSS125  = GND
  DQ31_B  = M_C_CPU0_SB_DQ<31>
  VSS126  = GND
  G1  = GND
  G2  = GND
  G3  = GND

(kicad_pcb
	(version 20260206)
	(generator "pcbnew")
	(generator_version "10.0")
	(general
		(thickness 1.6)
		(legacy_teardrops no)
	)
	(paper "A4")
	(title_block
		(title "04192023_DAF0TMB3IC0_F0TG_MB_C_brd_V02_OCP.brd")
		(comment 1 "Grand Teton / footprint 4167 of 8354 (J17), pads 1-46 of 291")
	)
	(layers
		(0 "F.Cu" signal "TOP")
		(4 "In1.Cu" signal "GND")
		(6 "In2.Cu" signal "IN1")
		(8 "In3.Cu" signal "GND1")
		(10 "In4.Cu" signal "IN2")
		(12 "In5.Cu" signal "GND2")
		(14 "In6.Cu" signal "IN3")
		(16 "In7.Cu" signal "GND3")
		(18 "In8.Cu" signal "VCC")
		(20 "In9.Cu" signal "VCC1")
		(22 "In10.Cu" signal "GND4")
		(24 "In11.Cu" signal "IN4")
		(26 "In12.Cu" signal "GND5")
		(28 "In13.Cu" signal "IN5")
		(30 "In14.Cu" signal "GND6")
		(32 "In15.Cu" signal "IN6")
		(34 "In16.Cu" signal "GND7")
		(2 "B.Cu" signal "BOTTOM")
		(9 "F.Adhes" user "F.Adhesive")
		(11 "B.Adhes" user "B.Adhesive")
		(13 "F.Paste" user "Package Geometry/Pastemask Top")
		(15 "B.Paste" user "Package Geometry/Pastemask Bottom")
		(5 "F.SilkS" user "Ref Des/Silkscreen Top")
		(7 "B.SilkS" user "Ref Des/Silkscreen Bottom")
		(1 "F.Mask" user "Board Geometry/Soldermask Top")
		(3 "B.Mask" user "Board Geometry/Soldermask Bottom")
		(17 "Dwgs.User" user "User.Drawings")
		(19 "Cmts.User" user "User.Comments")
		(21 "Eco1.User" user "User.Eco1")
		(23 "Eco2.User" user "User.Eco2")
		(25 "Edge.Cuts" user "Board Geometry/Outline")
		(27 "Margin" user)
		(31 "F.CrtYd" user "Package Geometry/Place Bound Top")
		(29 "B.CrtYd" user "Package Geometry/Place Bound Bottom")
		(35 "F.Fab" user "Ref Des/Assembly Top")
		(33 "B.Fab" user "Ref Des/Assembly Bottom")
	)
	(footprint ""
		(layer "F.Cu")
		(at 290.230052 -255.560068 180)
		(property "Reference" "J17"
			(at -2.2098 -81.984088 0)
			(unlocked yes)
			(layer "F.SilkS")
			(effects
				(font
					(size 0.7874 0.5842)
					(thickness 0.1524)
				)
			)
		)
		(property "Value" ""
			(at 0 0 180)
			(layer "F.Fab")
			(effects
				(font
					(size 1.27 1.27)
				)
			)
		)
		(duplicate_pad_numbers_are_jumpers no)
		(pad "1" smd rect
			(at -2.050034 -63.324994 90)
			(size 0.519938 1.4986)
			(layers "F.Cu" "F.Mask" "F.Paste")
			(net "P12V_MEM_CPU0")
		)
		(pad "2" smd rect
			(at -2.050034 -62.47511 90)
			(size 0.519938 1.4986)
			(layers "F.Cu" "F.Mask" "F.Paste")
			(net "Net_2277")
		)
		(pad "3" smd rect
			(at -2.050034 -61.624972 90)
			(size 0.519938 1.4986)
			(layers "F.Cu" "F.Mask" "F.Paste")
			(net "P3V3_AUX")
		)
		(pad "4" smd rect
			(at -2.050034 -60.775088 90)
			(size 0.519938 1.4986)
			(layers "F.Cu" "F.Mask" "F.Paste")
			(net "I3C_SPD_DDRC_CPU0_SCL")
		)
		(pad "5" smd rect
			(at -2.050034 -59.92495 90)
			(size 0.519938 1.4986)
			(layers "F.Cu" "F.Mask" "F.Paste")
			(net "I3C_SPD_DDRC_CPU0_SDA")
		)
		(pad "6" smd rect
			(at -2.050034 -59.075066 90)
			(size 0.519938 1.4986)
			(layers "F.Cu" "F.Mask" "F.Paste")
			(net "GND")
		)
		(pad "7" smd rect
			(at -2.050034 -58.224928 90)
			(size 0.519938 1.4986)
			(layers "F.Cu" "F.Mask" "F.Paste")
			(net "M_C_CPU0_SA_DQ<0>")
		)
		(pad "8" smd rect
			(at -2.050034 -57.375044 90)
			(size 0.519938 1.4986)
			(layers "F.Cu" "F.Mask" "F.Paste")
			(net "GND")
		)
		(pad "9" smd rect
			(at -2.050034 -56.524906 90)
			(size 0.519938 1.4986)
			(layers "F.Cu" "F.Mask" "F.Paste")
			(net "M_C_CPU0_SA_DQ<1>")
		)
		(pad "10" smd rect
			(at -2.050034 -55.675022 90)
			(size 0.519938 1.4986)
			(layers "F.Cu" "F.Mask" "F.Paste")
			(net "GND")
		)
		(pad "11" smd rect
			(at -2.050034 -54.824884 90)
			(size 0.519938 1.4986)
			(layers "F.Cu" "F.Mask" "F.Paste")
			(net "M_C_CPU0_SA_DQS_DP<0>")
		)
		(pad "12" smd rect
			(at -2.050034 -53.975 90)
			(size 0.519938 1.4986)
			(layers "F.Cu" "F.Mask" "F.Paste")
			(net "M_C_CPU0_SA_DQS_DN<0>")
		)
		(pad "13" smd rect
			(at -2.050034 -53.125116 90)
			(size 0.519938 1.4986)
			(layers "F.Cu" "F.Mask" "F.Paste")
			(net "GND")
		)
		(pad "14" smd rect
			(at -2.050034 -52.274978 90)
			(size 0.519938 1.4986)
			(layers "F.Cu" "F.Mask" "F.Paste")
			(net "M_C_CPU0_SA_DQ<4>")
		)
		(pad "15" smd rect
			(at -2.050034 -51.425094 90)
			(size 0.519938 1.4986)
			(layers "F.Cu" "F.Mask" "F.Paste")
			(net "GND")
		)
		(pad "16" smd rect
			(at -2.050034 -50.574956 90)
			(size 0.519938 1.4986)
			(layers "F.Cu" "F.Mask" "F.Paste")
			(net "M_C_CPU0_SA_DQ<5>")
		)
		(pad "17" smd rect
			(at -2.050034 -49.725072 90)
			(size 0.519938 1.4986)
			(layers "F.Cu" "F.Mask" "F.Paste")
			(net "GND")
		)
		(pad "18" smd rect
			(at -2.050034 -48.874934 90)
			(size 0.519938 1.4986)
			(layers "F.Cu" "F.Mask" "F.Paste")
			(net "M_C_CPU0_SA_DQ<8>")
		)
		(pad "19" smd rect
			(at -2.050034 -48.02505 90)
			(size 0.519938 1.4986)
			(layers "F.Cu" "F.Mask" "F.Paste")
			(net "GND")
		)
		(pad "20" smd rect
			(at -2.050034 -47.174912 90)
			(size 0.519938 1.4986)
			(layers "F.Cu" "F.Mask" "F.Paste")
			(net "M_C_CPU0_SA_DQ<9>")
		)
		(pad "21" smd rect
			(at -2.050034 -46.325028 90)
			(size 0.519938 1.4986)
			(layers "F.Cu" "F.Mask" "F.Paste")
			(net "GND")
		)
		(pad "22" smd rect
			(at -2.050034 -45.47489 90)
			(size 0.519938 1.4986)
			(layers "F.Cu" "F.Mask" "F.Paste")
			(net "M_C_CPU0_SA_DQS_DP<1>")
		)
		(pad "23" smd rect
			(at -2.050034 -44.625006 90)
			(size 0.519938 1.4986)
			(layers "F.Cu" "F.Mask" "F.Paste")
			(net "M_C_CPU0_SA_DQS_DN<1>")
		)
		(pad "24" smd rect
			(at -2.050034 -43.775122 90)
			(size 0.519938 1.4986)
			(layers "F.Cu" "F.Mask" "F.Paste")
			(net "GND")
		)
		(pad "25" smd rect
			(at -2.050034 -42.924984 90)
			(size 0.519938 1.4986)
			(layers "F.Cu" "F.Mask" "F.Paste")
			(net "M_C_CPU0_SA_DQ<12>")
		)
		(pad "26" smd rect
			(at -2.050034 -42.0751 90)
			(size 0.519938 1.4986)
			(layers "F.Cu" "F.Mask" "F.Paste")
			(net "GND")
		)
		(pad "27" smd rect
			(at -2.050034 -41.224962 90)
			(size 0.519938 1.4986)
			(layers "F.Cu" "F.Mask" "F.Paste")
			(net "M_C_CPU0_SA_DQ<13>")
		)
		(pad "28" smd rect
			(at -2.050034 -40.375078 90)
			(size 0.519938 1.4986)
			(layers "F.Cu" "F.Mask" "F.Paste")
			(net "GND")
		)
		(pad "29" smd rect
			(at -2.050034 -39.52494 90)
			(size 0.519938 1.4986)
			(layers "F.Cu" "F.Mask" "F.Paste")
			(net "M_C_CPU0_SA_DQ<16>")
		)
		(pad "30" smd rect
			(at -2.050034 -38.675056 90)
			(size 0.519938 1.4986)
			(layers "F.Cu" "F.Mask" "F.Paste")
			(net "GND")
		)
		(pad "31" smd rect
			(at -2.050034 -37.824918 90)
			(size 0.519938 1.4986)
			(layers "F.Cu" "F.Mask" "F.Paste")
			(net "M_C_CPU0_SA_DQ<17>")
		)
		(pad "32" smd rect
			(at -2.050034 -36.975034 90)
			(size 0.519938 1.4986)
			(layers "F.Cu" "F.Mask" "F.Paste")
			(net "GND")
		)
		(pad "33" smd rect
			(at -2.050034 -36.124896 90)
			(size 0.519938 1.4986)
			(layers "F.Cu" "F.Mask" "F.Paste")
			(net "M_C_CPU0_SA_DQS_DP<2>")
		)
		(pad "34" smd rect
			(at -2.050034 -35.275012 90)
			(size 0.519938 1.4986)
			(layers "F.Cu" "F.Mask" "F.Paste")
			(net "M_C_CPU0_SA_DQS_DN<2>")
		)
		(pad "35" smd rect
			(at -2.050034 -34.425128 90)
			(size 0.519938 1.4986)
			(layers "F.Cu" "F.Mask" "F.Paste")
			(net "GND")
		)
		(pad "36" smd rect
			(at -2.050034 -33.57499 90)
			(size 0.519938 1.4986)
			(layers "F.Cu" "F.Mask" "F.Paste")
			(net "M_C_CPU0_SA_DQ<20>")
		)
		(pad "37" smd rect
			(at -2.050034 -32.725106 90)
			(size 0.519938 1.4986)
			(layers "F.Cu" "F.Mask" "F.Paste")
			(net "GND")
		)
		(pad "38" smd rect
			(at -2.050034 -31.874968 90)
			(size 0.519938 1.4986)
			(layers "F.Cu" "F.Mask" "F.Paste")
			(net "M_C_CPU0_SA_DQ<21>")
		)
		(pad "39" smd rect
			(at -2.050034 -31.025084 90)
			(size 0.519938 1.4986)
			(layers "F.Cu" "F.Mask" "F.Paste")
			(net "GND")
		)
		(pad "40" smd rect
			(at -2.050034 -30.174946 90)
			(size 0.519938 1.4986)
			(layers "F.Cu" "F.Mask" "F.Paste")
			(net "M_C_CPU0_SA_DQ<24>")
		)
		(pad "41" smd rect
			(at -2.050034 -29.325062 90)
			(size 0.519938 1.4986)
			(layers "F.Cu" "F.Mask" "F.Paste")
			(net "GND")
		)
		(pad "42" smd rect
			(at -2.050034 -28.474924 90)
			(size 0.519938 1.4986)
			(layers "F.Cu" "F.Mask" "F.Paste")
			(net "M_C_CPU0_SA_DQ<25>")
		)
		(pad "43" smd rect
			(at -2.050034 -27.62504 90)
			(size 0.519938 1.4986)
			(layers "F.Cu" "F.Mask" "F.Paste")
			(net "GND")
		)
		(pad "44" smd rect
			(at -2.050034 -26.774902 90)
			(size 0.519938 1.4986)
			(layers "F.Cu" "F.Mask" "F.Paste")
			(net "M_C_CPU0_SA_DQS_DP<3>")
		)
		(pad "45" smd rect
			(at -2.050034 -25.925018 90)
			(size 0.519938 1.4986)
			(layers "F.Cu" "F.Mask" "F.Paste")
			(net "M_C_CPU0_SA_DQS_DN<3>")
		)
		(pad "46" smd rect
			(at -2.050034 -25.07488 90)
			(size 0.519938 1.4986)
			(layers "F.Cu" "F.Mask" "F.Paste")
			(net "GND")
		)
	)
)
